# SCM (Grand Teton) — schematic netlist excerpt (pin names and nets, part order shuffled) for the footprints in the layout excerpt that follows; sources: Cadence DE-HDL packaged netlist, KiCad conversion of 12092022_DA0F0TMDCD0_F0T_Management_Board_D_brd_V3_OCP.brd

R127  Q_RES  240 1% CHIP  pkg 0402LF  page 12 : A = GND ; B = IBMC_MIOZ
R265  Q_RES  2.2K 5% CHIP  pkg 0402LF  page 27 : A = P3V3_AUX ; B = SMB_BMC_MM16_SDA

(kicad_pcb
	(version 20260206)
	(generator "pcbnew")
	(generator_version "10.0")
	(general
		(thickness 1.6)
		(legacy_teardrops no)
	)
	(paper "A4")
	(title_block
		(title "12092022_DA0F0TMDCD0_F0T_Management_Board_D_brd_V3_OCP.brd")
		(comment 1 "Grand Teton / footprints 1235-1236 of 1440")
	)
	(layers
		(0 "F.Cu" signal "TOP")
		(4 "In1.Cu" signal "GND")
		(6 "In2.Cu" signal "IN1")
		(8 "In3.Cu" signal "GND1")
		(10 "In4.Cu" signal "IN2")
		(12 "In5.Cu" signal "VCC")
		(14 "In6.Cu" signal "VCC1")
		(16 "In7.Cu" signal "IN3")
		(18 "In8.Cu" signal "GND2")
		(20 "In9.Cu" signal "IN4")
		(22 "In10.Cu" signal "GND3")
		(2 "B.Cu" signal "BOTTOM")
		(9 "F.Adhes" user "F.Adhesive")
		(11 "B.Adhes" user "B.Adhesive")
		(13 "F.Paste" user "Package Geometry/Pastemask Top")
		(15 "B.Paste" user "Package Geometry/Pastemask Bottom")
		(5 "F.SilkS" user "Ref Des/Silkscreen Top")
		(7 "B.SilkS" user "Ref Des/Silkscreen Bottom")
		(1 "F.Mask" user "Board Geometry/Soldermask Top")
		(3 "B.Mask" user "Board Geometry/Soldermask Bottom")
		(17 "Dwgs.User" user "User.Drawings")
		(19 "Cmts.User" user "User.Comments")
		(21 "Eco1.User" user "User.Eco1")
		(23 "Eco2.User" user "User.Eco2")
		(25 "Edge.Cuts" user "Board Geometry/Outline")
		(27 "Margin" user)
		(31 "F.CrtYd" user "Package Geometry/Place Bound Top")
		(29 "B.CrtYd" user "Package Geometry/Place Bound Bottom")
		(35 "F.Fab" user "Ref Des/Assembly Top")
		(33 "B.Fab" user "Ref Des/Assembly Bottom")
	)
	(footprint ""
		(layer "B.Cu")
		(at 49.657 -30.861 -90)
		(property "Reference" "R265"
			(at 0 0 90)
			(layer "B.SilkS")
			(hide yes)
			(effects
				(font
					(size 1.27 1.27)
				)
				(justify mirror)
			)
		)
		(property "Value" ""
			(at 0 0 90)
			(layer "B.Fab")
			(effects
				(font
					(size 1.27 1.27)
				)
				(justify mirror)
			)
		)
		(duplicate_pad_numbers_are_jumpers no)
		(fp_line
			(start -0.7874 0.4064)
			(end 0.7874 0.4064)
			(stroke
				(width 0.1524)
				(type default)
			)
			(layer "B.SilkS")
		)
		(fp_line
			(start 0.7874 0.4064)
			(end 0.7874 -0.4064)
			(stroke
				(width 0.1524)
				(type default)
			)
			(layer "B.SilkS")
		)
		(fp_line
			(start -0.7874 -0.4064)
			(end -0.7874 0.4064)
			(stroke
				(width 0.1524)
				(type default)
			)
			(layer "B.SilkS")
		)
		(fp_line
			(start 0.7874 -0.4064)
			(end -0.7874 -0.4064)
			(stroke
				(width 0.1524)
				(type default)
			)
			(layer "B.SilkS")
		)
		(fp_line
			(start -0.67945 0.3048)
			(end -0.120396 0.3048)
			(stroke
				(width 0.1)
				(type default)
			)
			(layer "B.Fab")
		)
		(fp_line
			(start -0.120396 0.3048)
			(end -0.120396 0.2794)
			(stroke
				(width 0.1)
				(type default)
			)
			(layer "B.Fab")
		)
		(fp_line
			(start 0.12065 0.3048)
			(end 0.67945 0.3048)
			(stroke
				(width 0.1)
				(type default)
			)
			(layer "B.Fab")
		)
		(fp_line
			(start 0.67945 0.3048)
			(end 0.67945 -0.305054)
			(stroke
				(width 0.1)
				(type default)
			)
			(layer "B.Fab")
		)
		(fp_line
			(start -0.120396 0.2794)
			(end 0.12065 0.2794)
			(stroke
				(width 0.1)
				(type default)
			)
			(layer "B.Fab")
		)
		(fp_line
			(start 0.12065 0.2794)
			(end 0.12065 0.3048)
			(stroke
				(width 0.1)
				(type default)
			)
			(layer "B.Fab")
		)
		(fp_line
			(start -0.12065 -0.2794)
			(end -0.12065 -0.3048)
			(stroke
				(width 0.1)
				(type default)
			)
			(layer "B.Fab")
		)
		(fp_line
			(start 0.12065 -0.2794)
			(end -0.12065 -0.2794)
			(stroke
				(width 0.1)
				(type default)
			)
			(layer "B.Fab")
		)
		(fp_line
			(start -0.67945 -0.3048)
			(end -0.67945 0.3048)
			(stroke
				(width 0.1)
				(type default)
			)
			(layer "B.Fab")
		)
		(fp_line
			(start -0.12065 -0.3048)
			(end -0.67945 -0.3048)
			(stroke
				(width 0.1)
				(type default)
			)
			(layer "B.Fab")
		)
		(fp_line
			(start 0.12065 -0.305054)
			(end 0.12065 -0.2794)
			(stroke
				(width 0.1)
				(type default)
			)
			(layer "B.Fab")
		)
		(fp_line
			(start 0.67945 -0.305054)
			(end 0.12065 -0.305054)
			(stroke
				(width 0.1)
				(type default)
			)
			(layer "B.Fab")
		)
		(pad "1" smd circle
			(at 0.40005 0 90)
			(size 0 0)
			(layers "B.Cu" "B.Mask" "B.Paste")
			(net "P3V3_AUX")
		)
		(pad "2" smd circle
			(at -0.40005 0 90)
			(size 0 0)
			(layers "B.Cu" "B.Mask" "B.Paste")
			(net "SMB_BMC_MM16_SDA")
		)
	)
	(footprint ""
		(layer "B.Cu")
		(at 64.662304 -51.586638)
		(property "Reference" "R127"
			(at 0 0 0)
			(layer "B.SilkS")
			(hide yes)
			(effects
				(font
					(size 1.27 1.27)
				)
				(justify mirror)
			)
		)
		(property "Value" ""
			(at 0 0 0)
			(layer "B.Fab")
			(effects
				(font
					(size 1.27 1.27)
				)
				(justify mirror)
			)
		)
		(duplicate_pad_numbers_are_jumpers no)
		(fp_line
			(start -0.7874 -0.4064)
			(end -0.7874 0.4064)
			(stroke
				(width 0.1524)
				(type default)
			)
			(layer "B.SilkS")
		)
		(fp_line
			(start -0.7874 0.4064)
			(end 0.7874 0.4064)
			(stroke
				(width 0.1524)
				(type default)
			)
			(layer "B.SilkS")
		)
		(fp_line
			(start 0.7874 -0.4064)
			(end -0.7874 -0.4064)
			(stroke
				(width 0.1524)
				(type default)
			)
			(layer "B.SilkS")
		)
		(fp_line
			(start 0.7874 0.4064)
			(end 0.7874 -0.4064)
			(stroke
				(width 0.1524)
				(type default)
			)
			(layer "B.SilkS")
		)
		(fp_line
			(start -0.67945 -0.3048)
			(end -0.67945 0.3048)
			(stroke
				(width 0.1)
				(type default)
			)
			(layer "B.Fab")
		)
		(fp_line
			(start -0.67945 0.3048)
			(end -0.120396 0.3048)
			(stroke
				(width 0.1)
				(type default)
			)
			(layer "B.Fab")
		)
		(fp_line
			(start -0.12065 -0.3048)
			(end -0.67945 -0.3048)
			(stroke
				(width 0.1)
				(type default)
			)
			(layer "B.Fab")
		)
		(fp_line
			(start -0.12065 -0.2794)
			(end -0.12065 -0.3048)
			(stroke
				(width 0.1)
				(type default)
			)
			(layer "B.Fab")
		)
		(fp_line
			(start -0.120396 0.2794)
			(end 0.12065 0.2794)
			(stroke
				(width 0.1)
				(type default)
			)
			(layer "B.Fab")
		)
		(fp_line
			(start -0.120396 0.3048)
			(end -0.120396 0.2794)
			(stroke
				(width 0.1)
				(type default)
			)
			(layer "B.Fab")
		)
		(fp_line
			(start 0.12065 -0.305054)
			(end 0.12065 -0.2794)
			(stroke
				(width 0.1)
				(type default)
			)
			(layer "B.Fab")
		)
		(fp_line
			(start 0.12065 -0.2794)
			(end -0.12065 -0.2794)
			(stroke
				(width 0.1)
				(type default)
			)
			(layer "B.Fab")
		)
		(fp_line
			(start 0.12065 0.2794)
			(end 0.12065 0.3048)
			(stroke
				(width 0.1)
				(type default)
			)
			(layer "B.Fab")
		)
		(fp_line
			(start 0.12065 0.3048)
			(end 0.67945 0.3048)
			(stroke
				(width 0.1)
				(type default)
			)
			(layer "B.Fab")
		)
		(fp_line
			(start 0.67945 -0.305054)
			(end 0.12065 -0.305054)
			(stroke
				(width 0.1)
				(type default)
			)
			(layer "B.Fab")
		)
		(fp_line
			(start 0.67945 0.3048)
			(end 0.67945 -0.305054)
			(stroke
				(width 0.1)
				(type default)
			)
			(layer "B.Fab")
		)
		(pad "1" smd circle
			(at 0.40005 0 180)
			(size 0 0)
			(layers "B.Cu" "B.Mask" "B.Paste")
			(net "GND")
		)
		(pad "2" smd circle
			(at -0.40005 0 180)
			(size 0 0)
			(layers "B.Cu" "B.Mask" "B.Paste")
			(net "IBMC_MIOZ")
		)
	)
)
